# BASEBOARD_FAB2 (Tioga Pass) — schematic netlist excerpt (pin names and nets, part order shuffled) for the footprints in the layout excerpt that follows; sources: Cadence DE-HDL packaged netlist, KiCad conversion of Wiwynn_Tioga_Pass_MB.brd

R1M22  RES  49.9 1% CHIP  pkg 0402  page 113 : A = JTAG_MCP_TMS_R1 ; B = JTAG_MCP_TMS
C25W99  CAP_A  0.1UF 16V 10% X7R  pkg 0402V  page 254 : A = P3V3_STBY ; B = GND

(kicad_pcb
	(version 20260206)
	(generator "pcbnew")
	(generator_version "10.0")
	(general
		(thickness 1.6)
		(legacy_teardrops no)
	)
	(paper "A4")
	(title_block
		(title "Wiwynn_Tioga_Pass_MB.brd")
		(comment 1 "Tioga Pass / footprints 2851-2852 of 4770")
	)
	(layers
		(0 "F.Cu" signal "TOP")
		(4 "In1.Cu" signal "L2GND")
		(6 "In2.Cu" signal "L3")
		(8 "In3.Cu" signal "L4GND")
		(10 "In4.Cu" signal "L5")
		(12 "In5.Cu" signal "L6GND")
		(14 "In6.Cu" signal "L7VCC")
		(16 "In7.Cu" signal "L8VCC")
		(18 "In8.Cu" signal "L9GND")
		(20 "In9.Cu" signal "L10")
		(22 "In10.Cu" signal "L11GND")
		(24 "In11.Cu" signal "L12")
		(26 "In12.Cu" signal "L13GND")
		(2 "B.Cu" signal "BOTTOM")
		(9 "F.Adhes" user "F.Adhesive")
		(11 "B.Adhes" user "B.Adhesive")
		(13 "F.Paste" user "Package Geometry/Pastemask Top")
		(15 "B.Paste" user "Package Geometry/Pastemask Bottom")
		(5 "F.SilkS" user "Ref Des/Silkscreen Top")
		(7 "B.SilkS" user "Ref Des/Silkscreen Bottom")
		(1 "F.Mask" user "Board Geometry/Soldermask Top")
		(3 "B.Mask" user "Board Geometry/Soldermask Bottom")
		(17 "Dwgs.User" user "User.Drawings")
		(19 "Cmts.User" user "User.Comments")
		(21 "Eco1.User" user "User.Eco1")
		(23 "Eco2.User" user "User.Eco2")
		(25 "Edge.Cuts" user "Board Geometry/Outline")
		(27 "Margin" user)
		(31 "F.CrtYd" user "Package Geometry/Place Bound Top")
		(29 "B.CrtYd" user "Package Geometry/Place Bound Bottom")
		(35 "F.Fab" user "Ref Des/Assembly Top")
		(33 "B.Fab" user "Ref Des/Assembly Bottom")
	)
	(footprint ""
		(layer "B.Cu")
		(at 439.478928 -157.152848 -90)
		(property "Reference" "C25W99"
			(at 0.8382 -0.67818 270)
			(unlocked yes)
			(layer "B.SilkS")
			(effects
				(font
					(size 0.4064 0.254)
					(thickness 0.1524)
				)
				(justify left mirror)
			)
		)
		(property "Value" ""
			(at 0 0 90)
			(layer "B.Fab")
			(effects
				(font
					(size 1.27 1.27)
				)
				(justify mirror)
			)
		)
		(duplicate_pad_numbers_are_jumpers no)
		(fp_poly
			(pts
				(xy -0.3048 -0.1016) (xy -0.3048 0.9906) (xy 0.3048 0.9906) (xy 0.3048 -0.1016)
			)
			(stroke
				(width 0)
				(type default)
			)
			(fill no)
			(layer "B.CrtYd")
		)
		(fp_line
			(start -0.3048 0.9906)
			(end -0.3048 -0.1016)
			(stroke
				(width 0.1)
				(type default)
			)
			(layer "B.Fab")
		)
		(fp_line
			(start 0.3048 0.9906)
			(end -0.3048 0.9906)
			(stroke
				(width 0.1)
				(type default)
			)
			(layer "B.Fab")
		)
		(fp_line
			(start -0.3048 -0.1016)
			(end 0.3048 -0.1016)
			(stroke
				(width 0.1)
				(type default)
			)
			(layer "B.Fab")
		)
		(fp_line
			(start 0.3048 -0.1016)
			(end 0.3048 0.9906)
			(stroke
				(width 0.1)
				(type default)
			)
			(layer "B.Fab")
		)
		(pad "1" smd rect
			(at 0 0 90)
			(size 0.508 0.508)
			(layers "B.Cu" "B.Mask" "B.Paste")
			(net "P3V3_STBY")
		)
		(pad "2" smd rect
			(at 0 0.889 90)
			(size 0.508 0.508)
			(layers "B.Cu" "B.Mask" "B.Paste")
			(net "GND")
		)
		(zone
			(layer "B.Cu")
			(hatch none 0.5)
			(connect_pads
				(clearance 0)
			)
			(min_thickness 0.25)
			(keepout
				(tracks not_allowed)
				(vias allowed)
				(pads allowed)
				(copperpour not_allowed)
				(footprints allowed)
			)
			(placement
				(enabled no)
				(sheetname "")
			)
			(fill
				(thermal_gap 0.5)
				(thermal_bridge_width 0.5)
				(island_removal_mode 0)
			)
			(polygon
				(pts
					(xy 438.843928 -156.898848) (xy 438.843928 -157.406848) (xy 439.224928 -157.406848) (xy 439.224928 -156.898848)
				)
			)
		)
		(zone
			(layer "B.Cu")
			(hatch none 0.5)
			(connect_pads
				(clearance 0)
			)
			(min_thickness 0.25)
			(keepout
				(tracks allowed)
				(vias not_allowed)
				(pads allowed)
				(copperpour not_allowed)
				(footprints allowed)
			)
			(placement
				(enabled no)
				(sheetname "")
			)
			(fill
				(thermal_gap 0.5)
				(thermal_bridge_width 0.5)
				(island_removal_mode 0)
			)
			(polygon
				(pts
					(xy 439.224928 -156.898848) (xy 439.224928 -157.406848) (xy 438.843928 -157.406848) (xy 438.843928 -156.898848)
				)
			)
		)
	)
	(footprint ""
		(layer "B.Cu")
		(at 451.9422 -130.9624 180)
		(property "Reference" "R1M22"
			(at 0 0 0)
			(layer "B.SilkS")
			(hide yes)
			(effects
				(font
					(size 1.27 1.27)
				)
				(justify mirror)
			)
		)
		(property "Value" ""
			(at 0 0 0)
			(layer "B.Fab")
			(effects
				(font
					(size 1.27 1.27)
				)
				(justify mirror)
			)
		)
		(duplicate_pad_numbers_are_jumpers no)
		(fp_poly
			(pts
				(xy 0.2794 -0.1016) (xy -0.2794 -0.1016) (xy -0.2794 0.9906) (xy 0.2794 0.9906)
			)
			(stroke
				(width 0)
				(type default)
			)
			(fill no)
			(layer "B.CrtYd")
		)
		(fp_line
			(start 0.2794 0.9906)
			(end -0.2794 0.9906)
			(stroke
				(width 0.1)
				(type default)
			)
			(layer "B.Fab")
		)
		(fp_line
			(start 0.2794 -0.1016)
			(end 0.2794 0.9906)
			(stroke
				(width 0.1)
				(type default)
			)
			(layer "B.Fab")
		)
		(fp_line
			(start -0.2794 0.9906)
			(end -0.2794 -0.1016)
			(stroke
				(width 0.1)
				(type default)
			)
			(layer "B.Fab")
		)
		(fp_line
			(start -0.2794 -0.1016)
			(end 0.2794 -0.1016)
			(stroke
				(width 0.1)
				(type default)
			)
			(layer "B.Fab")
		)
		(pad "1" smd rect
			(at 0 0)
			(size 0.508 0.508)
			(layers "B.Cu" "B.Mask" "B.Paste")
			(net "JTAG_MCP_TMS_R1")
		)
		(pad "2" smd rect
			(at 0 0.889)
			(size 0.508 0.508)
			(layers "B.Cu" "B.Mask" "B.Paste")
			(net "JTAG_MCP_TMS")
		)
		(zone
			(layer "B.Cu")
			(hatch none 0.5)
			(connect_pads
				(clearance 0)
			)
			(min_thickness 0.25)
			(keepout
				(tracks not_allowed)
				(vias allowed)
				(pads allowed)
				(copperpour not_allowed)
				(footprints allowed)
			)
			(placement
				(enabled no)
				(sheetname "")
			)
			(fill
				(thermal_gap 0.5)
				(thermal_bridge_width 0.5)
				(island_removal_mode 0)
			)
			(polygon
				(pts
					(xy 451.6882 -131.5974) (xy 452.1962 -131.5974) (xy 452.1962 -131.2164) (xy 451.6882 -131.2164)
				)
			)
		)
		(zone
			(layer "B.Cu")
			(hatch none 0.5)
			(connect_pads
				(clearance 0)
			)
			(min_thickness 0.25)
			(keepout
				(tracks allowed)
				(vias not_allowed)
				(pads allowed)
				(copperpour not_allowed)
				(footprints allowed)
			)
			(placement
				(enabled no)
				(sheetname "")
			)
			(fill
				(thermal_gap 0.5)
				(thermal_bridge_width 0.5)
				(island_removal_mode 0)
			)
			(polygon
				(pts
					(xy 451.6882 -131.2164) (xy 452.1962 -131.2164) (xy 452.1962 -131.5974) (xy 451.6882 -131.5974)
				)
			)
		)
	)
)
